#ISCELL
  pure_quanta quanta_title_block_c *
  *
#ISCELL
  standard tap *
  page382_i10
#ISCELL
  standard tap *
  page382_i11
#ISCELL
  standard tap *
  page382_i12
#ISCELL
  standard tap *
  page382_i13
#ISCELL
  standard tap *
  page382_i14
#ISCELL
  standard tap *
  page382_i15
#ISCELL
  standard tap *
  page382_i16
#ISCELL
  standard tap *
  page382_i17
#CELL
  pure_quanta pt5161lrs *
  page382_i2
#ISCELL
  standard tap *
  page382_i20
#ISCELL
  standard tap *
  page382_i21
#ISCELL
  standard offpage *
  page382_i22
#ISCELL
  standard offpage *
  page382_i23
#ISCELL
  standard tap *
  page382_i24
#ISCELL
  standard tap *
  page382_i25
#ISCELL
  standard tap *
  page382_i26
#ISCELL
  standard tap *
  page382_i27
#ISCELL
  standard tap *
  page382_i28
#ISCELL
  standard tap *
  page382_i29
#CELL
  pure_quanta pt5161lrs *
  page382_i3
#ISCELL
  standard tap *
  page382_i30
#ISCELL
  standard tap *
  page382_i31
#ISCELL
  standard tap *
  page382_i32
#ISCELL
  standard tap *
  page382_i33
#ISCELL
  standard tap *
  page382_i34
#ISCELL
  standard tap *
  page382_i35
#ISCELL
  standard tap *
  page382_i36
#ISCELL
  standard tap *
  page382_i37
#ISCELL
  standard tap *
  page382_i38
#ISCELL
  standard tap *
  page382_i39
#ISCELL
  standard tap *
  page382_i4
#ISCELL
  standard offpage *
  page382_i42
#ISCELL
  standard offpage *
  page382_i43
#ISCELL
  standard tap *
  page382_i5
#ISCELL
  standard tap *
  page382_i6
#ISCELL
  standard tap *
  page382_i7
#ISCELL
  standard tap *
  page382_i8
#ISCELL
  standard tap *
  page382_i9
